(kicad_pcb
	(version 20221018)
	(generator pcbnew)
	(general
    (thickness 1.518)
  )
	(paper "A4")
	(title_block
    (title "Kria K26 Devboard")
    (date "2024-03-26")
    (rev "1.2.5")
    (comment 1 "www.antmicro.com")
    (comment 2 "Antmicro Ltd.")
		(comment 9 "footprints 144-153 of 660")
	)
	(layers
    (0 "F.Cu" mixed)
    (1 "In1.Cu" power)
    (2 "In2.Cu" mixed)
    (3 "In3.Cu" power)
    (4 "In4.Cu" mixed)
    (5 "In5.Cu" power)
    (6 "In6.Cu" mixed)
    (31 "B.Cu" power)
    (32 "B.Adhes" user "B.Adhesive")
    (33 "F.Adhes" user "F.Adhesive")
    (34 "B.Paste" user)
    (35 "F.Paste" user)
    (36 "B.SilkS" user "B.Silkscreen")
    (37 "F.SilkS" user "F.Silkscreen")
    (38 "B.Mask" user)
    (39 "F.Mask" user)
    (40 "Dwgs.User" user "User.Drawings")
    (41 "Cmts.User" user "User.Comments")
    (42 "Eco1.User" user "User.Eco1")
    (43 "Eco2.User" user "User.Eco2")
    (44 "Edge.Cuts" user)
    (45 "Margin" user)
    (46 "B.CrtYd" user "B.Courtyard")
    (47 "F.CrtYd" user "F.Courtyard")
    (48 "B.Fab" user)
    (49 "F.Fab" user)
  )
	(footprint "kria-k26-devboard-footprints:C_0402_1005Metric" (layer "F.Cu")
    (at 142.45 75.575 180)
    (descr "Capacitor SMD 0402")
    (tags "capacitor SMD 0402")
    (property "Author" "Antmicro")
    (property "Dielectric" "X5R")
    (property "License" "Apache-2.0")
    (property "MPN" "GRM155R61H104KE14D")
    (property "Manufacturer" "Murata")
    (property "Sheetfile" "usb.kicad_sch")
    (property "Sheetname" "USB")
    (property "Val" "100n")
    (property "Voltage" "50V")
    (property "ki_description" " ")
    (attr smd)
    (fp_text reference "C63" (at 1.1 -1.355 180) (layer "F.SilkS")
        (effects (font (size 0.7 0.7) (thickness 0.15)) (justify left bottom))
    )
    (fp_text value "C_100n_0402" (at 0 1.4 180) (layer "F.Fab") hide
        (effects (font (size 0.7 0.7) (thickness 0.15)) (justify left bottom))
    )
    (fp_text user "Author: Antmicro" (at -0.932 4.17 180) (layer "F.Fab") hide
        (effects (font (size 0.7 0.7) (thickness 0.15)) (justify left bottom))
    )
    (fp_text user "License: Apache-2.0" (at -0.932 5.17 180) (layer "F.Fab") hide
        (effects (font (size 0.7 0.7) (thickness 0.15)) (justify left bottom))
    )
    (fp_text user "${REFERENCE}" (at -0.932 3.168 180) (layer "F.Fab") hide
        (effects (font (size 0.7 0.7) (thickness 0.15)) (justify left bottom))
    )
    (fp_rect (start -0.94 -0.47) (end 0.94 0.47)
      (stroke (width 0.05) (type solid)) (fill none) (layer "F.CrtYd"))
    (fp_rect (start -0.499 -0.249) (end 0.499 0.249)
      (stroke (width 0.15) (type solid)) (fill none) (layer "F.Fab"))
    (pad "1" smd roundrect (at -0.484 0 180) (size 0.59 0.64) (layers "F.Cu" "F.Paste" "F.Mask") (roundrect_rratio 0.25)
      (net 306 "USB_5V") (pintype "passive"))
    (pad "2" smd roundrect (at 0.484 0 180) (size 0.59 0.64) (layers "F.Cu" "F.Paste" "F.Mask") (roundrect_rratio 0.25)
      (net 1 "GND") (pintype "passive"))
  )
	(footprint "kria-k26-devboard-footprints:R_0402_1005Metric" (layer "F.Cu")
    (at 118.36 76.79 -90)
    (descr "Resistor SMD 0402")
    (tags "resistor SMD 0402")
    (property "Author" "Antmicro")
    (property "License" "Apache-2.0")
    (property "MPN" "CR0402-FX-2003GLF")
    (property "Manufacturer" "Bourns")
    (property "Sheetfile" "usb.kicad_sch")
    (property "Sheetname" "USB")
    (property "Tolerance" "1%")
    (property "Val" "200k")
    (property "ki_description" "200k resistor in 0402 package with 1% tolerance")
    (attr smd)
    (fp_text reference "R56" (at 1.06 2.46 -90) (layer "F.SilkS")
        (effects (font (size 0.7 0.7) (thickness 0.15)) (justify left bottom))
    )
    (fp_text value "R_200k_0402" (at 0 1.4 -90) (layer "F.Fab") hide
        (effects (font (size 0.7 0.7) (thickness 0.15)) (justify left bottom))
    )
    (fp_text user "${REFERENCE}" (at -0.95 3.168 -90) (layer "F.Fab") hide
        (effects (font (size 0.7 0.7) (thickness 0.15)) (justify left bottom))
    )
    (fp_text user "Author: Antmicro" (at -0.95 4.169 -90) (layer "F.Fab") hide
        (effects (font (size 0.7 0.7) (thickness 0.15)) (justify left bottom))
    )
    (fp_text user "License: Apache-2.0" (at -0.95 5.169 -90) (layer "F.Fab") hide
        (effects (font (size 0.7 0.7) (thickness 0.15)) (justify left bottom))
    )
    (fp_rect (start -0.93 -0.47) (end 0.93 0.47)
      (stroke (width 0.05) (type solid)) (fill none) (layer "F.CrtYd"))
    (fp_rect (start -0.5 -0.25) (end 0.5 0.25)
      (stroke (width 0.15) (type solid)) (fill none) (layer "F.Fab"))
    (pad "1" smd roundrect (at -0.485 0 270) (size 0.59 0.64) (layers "F.Cu" "F.Paste" "F.Mask") (roundrect_rratio 0.25)
      (net 1 "GND") (pintype "passive"))
    (pad "2" smd roundrect (at 0.485 0 270) (size 0.59 0.64) (layers "F.Cu" "F.Paste" "F.Mask") (roundrect_rratio 0.25)
      (net 659 "Net-(U17-PF6)") (pintype "passive"))
  )
	(footprint "kria-k26-devboard-footprints:R_0402_1005Metric" (layer "F.Cu")
    (at 129.906942 88.724862 180)
    (descr "Resistor SMD 0402")
    (tags "resistor SMD 0402")
    (property "Author" "Antmicro")
    (property "License" "Apache-2.0")
    (property "MPN" "CR0402-FX-2003GLF")
    (property "Manufacturer" "Bourns")
    (property "Sheetfile" "usb.kicad_sch")
    (property "Sheetname" "USB")
    (property "Tolerance" "1%")
    (property "Val" "200k")
    (property "ki_description" "200k resistor in 0402 package with 1% tolerance")
    (attr smd)
    (fp_text reference "R61" (at -0.873058 -0.405138 180) (layer "F.SilkS")
        (effects (font (size 0.7 0.7) (thickness 0.15)) (justify left bottom))
    )
    (fp_text value "R_200k_0402" (at 0 1.4 180) (layer "F.Fab") hide
        (effects (font (size 0.7 0.7) (thickness 0.15)) (justify left bottom))
    )
    (fp_text user "Author: Antmicro" (at -0.95 4.169 180) (layer "F.Fab") hide
        (effects (font (size 0.7 0.7) (thickness 0.15)) (justify left bottom))
    )
    (fp_text user "License: Apache-2.0" (at -0.95 5.169 180) (layer "F.Fab") hide
        (effects (font (size 0.7 0.7) (thickness 0.15)) (justify left bottom))
    )
    (fp_text user "${REFERENCE}" (at -0.95 3.168 180) (layer "F.Fab") hide
        (effects (font (size 0.7 0.7) (thickness 0.15)) (justify left bottom))
    )
    (fp_rect (start -0.93 -0.47) (end 0.93 0.47)
      (stroke (width 0.05) (type solid)) (fill none) (layer "F.CrtYd"))
    (fp_rect (start -0.5 -0.25) (end 0.5 0.25)
      (stroke (width 0.15) (type solid)) (fill none) (layer "F.Fab"))
    (pad "1" smd roundrect (at -0.485 0 180) (size 0.59 0.64) (layers "F.Cu" "F.Paste" "F.Mask") (roundrect_rratio 0.25)
      (net 1 "GND") (pintype "passive"))
    (pad "2" smd roundrect (at 0.485 0 180) (size 0.59 0.64) (layers "F.Cu" "F.Paste" "F.Mask") (roundrect_rratio 0.25)
      (net 664 "Net-(U17-PF31)") (pintype "passive"))
  )
	(footprint "kria-k26-devboard-footprints:R_0402_1005Metric" (layer "F.Cu")
    (at 117.286942 76.79 -90)
    (descr "Resistor SMD 0402")
    (tags "resistor SMD 0402")
    (property "Author" "Antmicro")
    (property "License" "Apache-2.0")
    (property "MPN" "CR0402-FX-2003GLF")
    (property "Manufacturer" "Bourns")
    (property "Sheetfile" "usb.kicad_sch")
    (property "Sheetname" "USB")
    (property "Tolerance" "1%")
    (property "Val" "200k")
    (property "ki_description" "200k resistor in 0402 package with 1% tolerance")
    (attr smd)
    (fp_text reference "R58" (at 1.06 2.46 -90) (layer "F.SilkS")
        (effects (font (size 0.7 0.7) (thickness 0.15)) (justify left bottom))
    )
    (fp_text value "R_200k_0402" (at 0 1.4 -90) (layer "F.Fab") hide
        (effects (font (size 0.7 0.7) (thickness 0.15)) (justify left bottom))
    )
    (fp_text user "${REFERENCE}" (at -0.95 3.168 -90) (layer "F.Fab") hide
        (effects (font (size 0.7 0.7) (thickness 0.15)) (justify left bottom))
    )
    (fp_text user "Author: Antmicro" (at -0.95 4.169 -90) (layer "F.Fab") hide
        (effects (font (size 0.7 0.7) (thickness 0.15)) (justify left bottom))
    )
    (fp_text user "License: Apache-2.0" (at -0.95 5.169 -90) (layer "F.Fab") hide
        (effects (font (size 0.7 0.7) (thickness 0.15)) (justify left bottom))
    )
    (fp_rect (start -0.93 -0.47) (end 0.93 0.47)
      (stroke (width 0.05) (type solid)) (fill none) (layer "F.CrtYd"))
    (fp_rect (start -0.5 -0.25) (end 0.5 0.25)
      (stroke (width 0.15) (type solid)) (fill none) (layer "F.Fab"))
    (pad "1" smd roundrect (at -0.485 0 270) (size 0.59 0.64) (layers "F.Cu" "F.Paste" "F.Mask") (roundrect_rratio 0.25)
      (net 1 "GND") (pintype "passive"))
    (pad "2" smd roundrect (at 0.485 0 270) (size 0.59 0.64) (layers "F.Cu" "F.Paste" "F.Mask") (roundrect_rratio 0.25)
      (net 661 "Net-(U17-PF8)") (pintype "passive"))
  )
	(footprint "kria-k26-devboard-footprints:R_0402_1005Metric" (layer "F.Cu")
    (at 119.32 76.79 -90)
    (descr "Resistor SMD 0402")
    (tags "resistor SMD 0402")
    (property "Author" "Antmicro")
    (property "License" "Apache-2.0")
    (property "MPN" "CR0402-FX-2003GLF")
    (property "Manufacturer" "Bourns")
    (property "Sheetfile" "usb.kicad_sch")
    (property "Sheetname" "USB")
    (property "Tolerance" "1%")
    (property "Val" "200k")
    (property "ki_description" "200k resistor in 0402 package with 1% tolerance")
    (attr smd)
    (fp_text reference "R54" (at 1.06 2.46 -90) (layer "F.SilkS")
        (effects (font (size 0.7 0.7) (thickness 0.15)) (justify left bottom))
    )
    (fp_text value "R_200k_0402" (at 0 1.4 -90) (layer "F.Fab") hide
        (effects (font (size 0.7 0.7) (thickness 0.15)) (justify left bottom))
    )
    (fp_text user "License: Apache-2.0" (at -0.95 5.169 -90) (layer "F.Fab") hide
        (effects (font (size 0.7 0.7) (thickness 0.15)) (justify left bottom))
    )
    (fp_text user "Author: Antmicro" (at -0.95 4.169 -90) (layer "F.Fab") hide
        (effects (font (size 0.7 0.7) (thickness 0.15)) (justify left bottom))
    )
    (fp_text user "${REFERENCE}" (at -0.95 3.168 -90) (layer "F.Fab") hide
        (effects (font (size 0.7 0.7) (thickness 0.15)) (justify left bottom))
    )
    (fp_rect (start -0.93 -0.47) (end 0.93 0.47)
      (stroke (width 0.05) (type solid)) (fill none) (layer "F.CrtYd"))
    (fp_rect (start -0.5 -0.25) (end 0.5 0.25)
      (stroke (width 0.15) (type solid)) (fill none) (layer "F.Fab"))
    (pad "1" smd roundrect (at -0.485 0 270) (size 0.59 0.64) (layers "F.Cu" "F.Paste" "F.Mask") (roundrect_rratio 0.25)
      (net 1 "GND") (pintype "passive"))
    (pad "2" smd roundrect (at 0.485 0 270) (size 0.59 0.64) (layers "F.Cu" "F.Paste" "F.Mask") (roundrect_rratio 0.25)
      (net 657 "Net-(U17-PF4)") (pintype "passive"))
  )
	(footprint "kria-k26-devboard-footprints:R_0402_1005Metric" (layer "F.Cu")
    (at 114.406942 85.024862)
    (descr "Resistor SMD 0402")
    (tags "resistor SMD 0402")
    (property "Author" "Antmicro")
    (property "License" "Apache-2.0")
    (property "MPN" "CR0402-FX-1002GLF")
    (property "Manufacturer" "Bourns")
    (property "Sheetfile" "usb.kicad_sch")
    (property "Sheetname" "USB")
    (property "Tolerance" "1%")
    (property "Val" "10k")
    (property "ki_description" "10k resistor in 0402 package with 1% tolerance")
    (attr smd)
    (fp_text reference "R47" (at -3.086942 0.335138) (layer "F.SilkS")
        (effects (font (size 0.7 0.7) (thickness 0.15)) (justify left bottom))
    )
    (fp_text value "R_10k_0402" (at 0 1.4) (layer "F.Fab") hide
        (effects (font (size 0.7 0.7) (thickness 0.15)) (justify left bottom))
    )
    (fp_text user "${REFERENCE}" (at -0.95 3.168) (layer "F.Fab") hide
        (effects (font (size 0.7 0.7) (thickness 0.15)) (justify left bottom))
    )
    (fp_text user "License: Apache-2.0" (at -0.95 5.169) (layer "F.Fab") hide
        (effects (font (size 0.7 0.7) (thickness 0.15)) (justify left bottom))
    )
    (fp_text user "Author: Antmicro" (at -0.95 4.169) (layer "F.Fab") hide
        (effects (font (size 0.7 0.7) (thickness 0.15)) (justify left bottom))
    )
    (fp_rect (start -0.93 -0.47) (end 0.93 0.47)
      (stroke (width 0.05) (type solid)) (fill none) (layer "F.CrtYd"))
    (fp_rect (start -0.5 -0.25) (end 0.5 0.25)
      (stroke (width 0.15) (type solid)) (fill none) (layer "F.Fab"))
    (pad "1" smd roundrect (at -0.485 0) (size 0.59 0.64) (layers "F.Cu" "F.Paste" "F.Mask") (roundrect_rratio 0.25)
      (net 1 "GND") (pintype "passive"))
    (pad "2" smd roundrect (at 0.485 0) (size 0.59 0.64) (layers "F.Cu" "F.Paste" "F.Mask") (roundrect_rratio 0.25)
      (net 650 "Net-(U17-TEST2)") (pintype "passive"))
  )
	(footprint "kria-k26-devboard-footprints:R_0402_1005Metric" (layer "F.Cu")
    (at 129.95 81.8 180)
    (descr "Resistor SMD 0402")
    (tags "resistor SMD 0402")
    (property "Author" "Antmicro")
    (property "License" "Apache-2.0")
    (property "MPN" "CR0402-FX-2003GLF")
    (property "Manufacturer" "Bourns")
    (property "Sheetfile" "usb.kicad_sch")
    (property "Sheetname" "USB")
    (property "Tolerance" "1%")
    (property "Val" "200k")
    (property "ki_description" "200k resistor in 0402 package with 1% tolerance")
    (attr smd)
    (fp_text reference "R50" (at -0.8 -0.37 180) (layer "F.SilkS")
        (effects (font (size 0.7 0.7) (thickness 0.15)) (justify left bottom))
    )
    (fp_text value "R_200k_0402" (at 0 1.4 180) (layer "F.Fab") hide
        (effects (font (size 0.7 0.7) (thickness 0.15)) (justify left bottom))
    )
    (fp_text user "${REFERENCE}" (at -0.95 3.168 180) (layer "F.Fab") hide
        (effects (font (size 0.7 0.7) (thickness 0.15)) (justify left bottom))
    )
    (fp_text user "License: Apache-2.0" (at -0.95 5.169 180) (layer "F.Fab") hide
        (effects (font (size 0.7 0.7) (thickness 0.15)) (justify left bottom))
    )
    (fp_text user "Author: Antmicro" (at -0.95 4.169 180) (layer "F.Fab") hide
        (effects (font (size 0.7 0.7) (thickness 0.15)) (justify left bottom))
    )
    (fp_rect (start -0.93 -0.47) (end 0.93 0.47)
      (stroke (width 0.05) (type solid)) (fill none) (layer "F.CrtYd"))
    (fp_rect (start -0.5 -0.25) (end 0.5 0.25)
      (stroke (width 0.15) (type solid)) (fill none) (layer "F.Fab"))
    (pad "1" smd roundrect (at -0.485 0 180) (size 0.59 0.64) (layers "F.Cu" "F.Paste" "F.Mask") (roundrect_rratio 0.25)
      (net 1 "GND") (pintype "passive"))
    (pad "2" smd roundrect (at 0.485 0 180) (size 0.59 0.64) (layers "F.Cu" "F.Paste" "F.Mask") (roundrect_rratio 0.25)
      (net 653 "Net-(U17-CFG_STRAP2)") (pintype "passive"))
  )
	(footprint "kria-k26-devboard-footprints:R_0402_1005Metric" (layer "F.Cu")
    (at 129.95 80.8 180)
    (descr "Resistor SMD 0402")
    (tags "resistor SMD 0402")
    (property "Author" "Antmicro")
    (property "License" "Apache-2.0")
    (property "MPN" "CR0402-FX-2003GLF")
    (property "Manufacturer" "Bourns")
    (property "Sheetfile" "usb.kicad_sch")
    (property "Sheetname" "USB")
    (property "Tolerance" "1%")
    (property "Val" "200k")
    (property "ki_description" "200k resistor in 0402 package with 1% tolerance")
    (attr smd)
    (fp_text reference "R51" (at -0.8 -0.37 180) (layer "F.SilkS")
        (effects (font (size 0.7 0.7) (thickness 0.15)) (justify left bottom))
    )
    (fp_text value "R_200k_0402" (at 0 1.4 180) (layer "F.Fab") hide
        (effects (font (size 0.7 0.7) (thickness 0.15)) (justify left bottom))
    )
    (fp_text user "License: Apache-2.0" (at -0.95 5.169 180) (layer "F.Fab") hide
        (effects (font (size 0.7 0.7) (thickness 0.15)) (justify left bottom))
    )
    (fp_text user "${REFERENCE}" (at -0.95 3.168 180) (layer "F.Fab") hide
        (effects (font (size 0.7 0.7) (thickness 0.15)) (justify left bottom))
    )
    (fp_text user "Author: Antmicro" (at -0.95 4.169 180) (layer "F.Fab") hide
        (effects (font (size 0.7 0.7) (thickness 0.15)) (justify left bottom))
    )
    (fp_rect (start -0.93 -0.47) (end 0.93 0.47)
      (stroke (width 0.05) (type solid)) (fill none) (layer "F.CrtYd"))
    (fp_rect (start -0.5 -0.25) (end 0.5 0.25)
      (stroke (width 0.15) (type solid)) (fill none) (layer "F.Fab"))
    (pad "1" smd roundrect (at -0.485 0 180) (size 0.59 0.64) (layers "F.Cu" "F.Paste" "F.Mask") (roundrect_rratio 0.25)
      (net 1 "GND") (pintype "passive"))
    (pad "2" smd roundrect (at 0.485 0 180) (size 0.59 0.64) (layers "F.Cu" "F.Paste" "F.Mask") (roundrect_rratio 0.25)
      (net 654 "Net-(U17-CFG_STRAP3)") (pintype "passive"))
  )
	(footprint "kria-k26-devboard-footprints:C_0603_1608Metric" (layer "F.Cu")
    (at 169.25 137.65)
    (descr "Capacitor SMD 0603")
    (tags "capacitor 0603")
    (property "Author" "Antmicro")
    (property "Dielectric" "")
    (property "License" "Apache-2.0")
    (property "MPN" "GRM188R60J226MEA0D")
    (property "Manufacturer" "Murata")
    (property "Sheetfile" "dc-dc-conventers.kicad_sch")
    (property "Sheetname" "DC/DC conventers")
    (property "Val" "22u")
    (property "Voltage" "")
    (property "ki_description" " ")
    (attr smd)
    (fp_text reference "C216" (at 0.69 2.55) (layer "F.SilkS")
        (effects (font (size 0.7 0.7) (thickness 0.15)) (justify left bottom))
    )
    (fp_text value "C_22u_0603" (at 0 1.6) (layer "F.Fab") hide
        (effects (font (size 0.7 0.7) (thickness 0.15)) (justify left bottom))
    )
    (fp_text user "${REFERENCE}" (at -1.682 3.895) (layer "F.Fab") hide
        (effects (font (size 0.7 0.7) (thickness 0.15)) (justify left bottom))
    )
    (fp_text user "Author: Antmicro" (at -1.682 4.894) (layer "F.Fab") hide
        (effects (font (size 0.7 0.7) (thickness 0.15)) (justify left bottom))
    )
    (fp_text user "License: Apache-2.0" (at -1.682 5.895) (layer "F.Fab") hide
        (effects (font (size 0.7 0.7) (thickness 0.15)) (justify left bottom))
    )
    (fp_line (start -0.3 -0.3) (end 0.3 -0.3)
      (stroke (width 0.15) (type solid)) (layer "F.SilkS"))
    (fp_line (start -0.3 0.3) (end 0.3 0.3)
      (stroke (width 0.15) (type solid)) (layer "F.SilkS"))
    (fp_rect (start -1.24 -0.7) (end 1.24 0.7)
      (stroke (width 0.05) (type solid)) (fill none) (layer "F.CrtYd"))
    (fp_rect (start -0.8 -0.4) (end 0.8 0.4)
      (stroke (width 0.15) (type solid)) (fill none) (layer "F.Fab"))
    (pad "1" smd roundrect (at -0.7 0) (size 0.6 0.8) (layers "F.Cu" "F.Paste" "F.Mask") (roundrect_rratio 0.2)
      (net 765 "/Power Supply/DC/DC conventers/PS_3V3_OUT") (pintype "passive"))
    (pad "2" smd roundrect (at 0.7 0) (size 0.6 0.8) (layers "F.Cu" "F.Paste" "F.Mask") (roundrect_rratio 0.2)
      (net 1 "GND") (pintype "passive"))
  )
	(footprint "kria-k26-devboard-footprints:C_0603_1608Metric" (layer "F.Cu")
    (at 169.25 139.06)
    (descr "Capacitor SMD 0603")
    (tags "capacitor 0603")
    (property "Author" "Antmicro")
    (property "Dielectric" "")
    (property "License" "Apache-2.0")
    (property "MPN" "GRM188R60J226MEA0D")
    (property "Manufacturer" "Murata")
    (property "Sheetfile" "dc-dc-conventers.kicad_sch")
    (property "Sheetname" "DC/DC conventers")
    (property "Val" "22u")
    (property "Voltage" "")
    (property "ki_description" " ")
    (attr smd)
    (fp_text reference "C211" (at 0.69 2.04) (layer "F.SilkS")
        (effects (font (size 0.7 0.7) (thickness 0.15)) (justify left bottom))
    )
    (fp_text value "C_22u_0603" (at 0 1.6) (layer "F.Fab") hide
        (effects (font (size 0.7 0.7) (thickness 0.15)) (justify left bottom))
    )
    (fp_text user "${REFERENCE}" (at -1.682 3.895) (layer "F.Fab") hide
        (effects (font (size 0.7 0.7) (thickness 0.15)) (justify left bottom))
    )
    (fp_text user "License: Apache-2.0" (at -1.682 5.895) (layer "F.Fab") hide
        (effects (font (size 0.7 0.7) (thickness 0.15)) (justify left bottom))
    )
    (fp_text user "Author: Antmicro" (at -1.682 4.894) (layer "F.Fab") hide
        (effects (font (size 0.7 0.7) (thickness 0.15)) (justify left bottom))
    )
    (fp_line (start -0.3 -0.3) (end 0.3 -0.3)
      (stroke (width 0.15) (type solid)) (layer "F.SilkS"))
    (fp_line (start -0.3 0.3) (end 0.3 0.3)
      (stroke (width 0.15) (type solid)) (layer "F.SilkS"))
    (fp_rect (start -1.24 -0.7) (end 1.24 0.7)
      (stroke (width 0.05) (type solid)) (fill none) (layer "F.CrtYd"))
    (fp_rect (start -0.8 -0.4) (end 0.8 0.4)
      (stroke (width 0.15) (type solid)) (fill none) (layer "F.Fab"))
    (pad "1" smd roundrect (at -0.7 0) (size 0.6 0.8) (layers "F.Cu" "F.Paste" "F.Mask") (roundrect_rratio 0.2)
      (net 765 "/Power Supply/DC/DC conventers/PS_3V3_OUT") (pintype "passive"))
    (pad "2" smd roundrect (at 0.7 0) (size 0.6 0.8) (layers "F.Cu" "F.Paste" "F.Mask") (roundrect_rratio 0.2)
      (net 1 "GND") (pintype "passive"))
  )
)
